# S9S_MB_2U (Grand Teton) — schematic netlist excerpt (pin names and nets, part order shuffled) for the footprints in the layout excerpt that follows; sources: Cadence DE-HDL packaged netlist, KiCad conversion of 03242023_DA0F0TMBIJ0_F0T_Motherboard_J_brd_V01_OCP.brd

J108  CONN112_10137002101LF  CONN112_10137002-101LF IO  pkg HSD_F112D8_P2W1-2_RDH  page 139
  A1  = GPU_3V3IO_RSVD3_FFU
  A2  = GND
  A3  = PRSNT_CABLE_GPU_A2_N
  A4  = GND
  A5  = GPU_3V3IO_RSVD5_FFU
  A6  = GND
  A7  = GPU_FPGA_OVERT_N
  A8  = GND
  B1  = GND
  B2  = P5E_CPU0_PE0_RX_DN<14>
  B3  = GND
  B4  = P5E_CPU0_PE0_RX_DN<12>
  B5  = GND
  B6  = P5E_CPU0_PE0_RX_DN<10>
  B7  = GND
  B8  = P5E_CPU0_PE0_RX_DN<8>
  C1  = P5E_CPU0_PE0_RX_DN<15>
  C2  = P5E_CPU0_PE0_RX_DP<14>
  C3  = P5E_CPU0_PE0_RX_DN<13>
  C4  = P5E_CPU0_PE0_RX_DP<12>
  C5  = P5E_CPU0_PE0_RX_DP<11>
  C6  = P5E_CPU0_PE0_RX_DP<10>
  C7  = P5E_CPU0_PE0_RX_DN<9>
  C8  = P5E_CPU0_PE0_RX_DP<8>
  D1  = P5E_CPU0_PE0_RX_DP<15>
  D2  = GND
  D3  = P5E_CPU0_PE0_RX_DP<13>
  D4  = GND
  D5  = P5E_CPU0_PE0_RX_DN<11>
  D6  = GND
  D7  = P5E_CPU0_PE0_RX_DP<9>
  D8  = GND
  E1  = GND
  E2  = P5E_CPU0_PE4_RX_DP<1>
  E3  = GND
  E4  = P5E_CPU0_PE4_RX_DP<3>
  E5  = GND
  E6  = P5E_CPU0_PE4_RX_DP<5>
  E7  = GND
  E8  = P5E_CPU0_PE4_RX_DP<7>
  F1  = P5E_CPU0_PE4_RX_DN<0>
  F2  = P5E_CPU0_PE4_RX_DN<1>
  F3  = P5E_CPU0_PE4_RX_DN<2>
  F4  = P5E_CPU0_PE4_RX_DN<3>
  F5  = P5E_CPU0_PE4_RX_DN<4>
  F6  = P5E_CPU0_PE4_RX_DN<5>
  F7  = P5E_CPU0_PE4_RX_DN<6>
  F8  = P5E_CPU0_PE4_RX_DN<7>
  G1  = P5E_CPU0_PE4_RX_DP<0>
  G2  = GND
  G3  = P5E_CPU0_PE4_RX_DP<2>
  G4  = GND
  G5  = P5E_CPU0_PE4_RX_DP<4>
  G6  = GND
  G7  = P5E_CPU0_PE4_RX_DP<6>
  G8  = GND
  H1  = GND
  H2  = P5E_CPU0_PE0_TX_C_DN<14>
  H3  = GND
  H4  = P5E_CPU0_PE0_TX_C_DN<12>
  H5  = GND
  H6  = P5E_CPU0_PE0_TX_C_DN<10>
  H7  = GND
  H8  = P5E_CPU0_PE0_TX_C_DN<8>
  I1  = P5E_CPU0_PE0_TX_C_DN<15>
  I2  = P5E_CPU0_PE0_TX_C_DP<14>
  I3  = P5E_CPU0_PE0_TX_C_DN<13>
  I4  = P5E_CPU0_PE0_TX_C_DP<12>
  I5  = P5E_CPU0_PE0_TX_C_DN<11>
  I6  = P5E_CPU0_PE0_TX_C_DP<10>
  I7  = P5E_CPU0_PE0_TX_C_DN<9>
  I8  = P5E_CPU0_PE0_TX_C_DP<8>
  J1  = P5E_CPU0_PE0_TX_C_DP<15>
  J2  = GND
  J3  = P5E_CPU0_PE0_TX_C_DP<13>
  J4  = GND
  J5  = P5E_CPU0_PE0_TX_C_DP<11>
  J6  = GND
  J7  = P5E_CPU0_PE0_TX_C_DP<9>
  J8  = GND
  K1  = GND
  K2  = P5E_CPU0_PE4_TX_C_DP<1>
  K3  = GND
  K4  = P5E_CPU0_PE4_TX_C_DN<3>
  K5  = GND
  K6  = P5E_CPU0_PE4_TX_C_DN<5>
  K7  = GND
  K8  = P5E_CPU0_PE4_TX_C_DN<7>
  L1  = P5E_CPU0_PE4_TX_C_DN<0>
  L2  = P5E_CPU0_PE4_TX_C_DN<1>
  L3  = P5E_CPU0_PE4_TX_C_DN<2>
  L4  = P5E_CPU0_PE4_TX_C_DP<3>
  L5  = P5E_CPU0_PE4_TX_C_DN<4>
  L6  = P5E_CPU0_PE4_TX_C_DP<5>
  L7  = P5E_CPU0_PE4_TX_C_DN<6>
  L8  = P5E_CPU0_PE4_TX_C_DP<7>
  M1  = P5E_CPU0_PE4_TX_C_DP<0>
  M2  = GND
  M3  = P5E_CPU0_PE4_TX_C_DP<2>
  M4  = GND
  M5  = P5E_CPU0_PE4_TX_C_DP<4>
  M6  = GND
  M7  = P5E_CPU0_PE4_TX_C_DP<6>
  M8  = GND
  N1  = GND
  N2  = NC_J108_N2
  N3  = GND
  N4  = NC_J108_N4
  N5  = GND
  N6  = NC_J108_N6
  N7  = GND
  N8  = PRSNT_CABLE_GPU_A3_N

(kicad_pcb
	(version 20260206)
	(generator "pcbnew")
	(generator_version "10.0")
	(general
		(thickness 1.6)
		(legacy_teardrops no)
	)
	(paper "A4")
	(title_block
		(title "03242023_DA0F0TMBIJ0_F0T_Motherboard_J_brd_V01_OCP.brd")
		(comment 1 "Grand Teton / footprint 2591 of 6105 (J108), pads 32-48 of 48")
	)
	(layers
		(0 "F.Cu" signal "TOP")
		(4 "In1.Cu" signal "GND")
		(6 "In2.Cu" signal "IN1")
		(8 "In3.Cu" signal "GND1")
		(10 "In4.Cu" signal "IN2")
		(12 "In5.Cu" signal "GND2")
		(14 "In6.Cu" signal "IN3")
		(16 "In7.Cu" signal "GND3")
		(18 "In8.Cu" signal "VCC")
		(20 "In9.Cu" signal "VCC1")
		(22 "In10.Cu" signal "GND4")
		(24 "In11.Cu" signal "IN4")
		(26 "In12.Cu" signal "GND5")
		(28 "In13.Cu" signal "IN5")
		(30 "In14.Cu" signal "GND6")
		(32 "In15.Cu" signal "IN6")
		(34 "In16.Cu" signal "GND7")
		(2 "B.Cu" signal "BOTTOM")
		(9 "F.Adhes" user "F.Adhesive")
		(11 "B.Adhes" user "B.Adhesive")
		(13 "F.Paste" user "Package Geometry/Pastemask Top")
		(15 "B.Paste" user "Package Geometry/Pastemask Bottom")
		(5 "F.SilkS" user "Ref Des/Silkscreen Top")
		(7 "B.SilkS" user "Ref Des/Silkscreen Bottom")
		(1 "F.Mask" user "Board Geometry/Soldermask Top")
		(3 "B.Mask" user "Board Geometry/Soldermask Bottom")
		(17 "Dwgs.User" user "User.Drawings")
		(19 "Cmts.User" user "User.Comments")
		(21 "Eco1.User" user "User.Eco1")
		(23 "Eco2.User" user "User.Eco2")
		(25 "Edge.Cuts" user "Board Geometry/Outline")
		(27 "Margin" user)
		(31 "F.CrtYd" user "Package Geometry/Place Bound Top")
		(29 "B.CrtYd" user "Package Geometry/Place Bound Bottom")
		(35 "F.Fab" user "Ref Des/Assembly Top")
		(33 "B.Fab" user "Ref Des/Assembly Bottom")
	)
	(footprint ""
		(layer "F.Cu")
		(at 314.65012 -440.489848)
		(property "Reference" "J108"
			(at 12.6238 23.28799 0)
			(unlocked yes)
			(layer "F.SilkS")
			(effects
				(font
					(size 0.7874 0.5842)
					(thickness 0.1524)
				)
				(justify left)
			)
		)
		(property "Value" ""
			(at 0 0 0)
			(layer "F.Fab")
			(effects
				(font
					(size 1.27 1.27)
				)
			)
		)
		(duplicate_pad_numbers_are_jumpers no)
		(pad "J8" thru_hole circle
			(at 13.999972 10.999978 180)
			(size 0.906272 0.906272)
			(drill 0.499872)
			(layers "*.Cu" "*.Mask")
			(remove_unused_layers no)
			(net "GND")
			(clearance 0.0508)
			(thermal_gap 0.0508)
		)
		(pad "K1" thru_hole circle
			(at 0 11.999976 180)
			(size 0.906272 0.906272)
			(drill 0.499872)
			(layers "*.Cu" "*.Mask")
			(remove_unused_layers no)
			(net "GND")
			(clearance 0.0508)
			(thermal_gap 0.0508)
		)
		(pad "K3" thru_hole circle
			(at 3.999992 11.999976 180)
			(size 0.906272 0.906272)
			(drill 0.499872)
			(layers "*.Cu" "*.Mask")
			(remove_unused_layers no)
			(net "GND")
			(clearance 0.0508)
			(thermal_gap 0.0508)
		)
		(pad "K5" thru_hole circle
			(at 7.999984 11.999976 180)
			(size 0.906272 0.906272)
			(drill 0.499872)
			(layers "*.Cu" "*.Mask")
			(remove_unused_layers no)
			(net "GND")
			(clearance 0.0508)
			(thermal_gap 0.0508)
		)
		(pad "K7" thru_hole circle
			(at 11.999976 11.999976 180)
			(size 0.906272 0.906272)
			(drill 0.499872)
			(layers "*.Cu" "*.Mask")
			(remove_unused_layers no)
			(net "GND")
			(clearance 0.0508)
			(thermal_gap 0.0508)
		)
		(pad "M2" thru_hole circle
			(at 1.999996 14.59992 180)
			(size 0.906272 0.906272)
			(drill 0.499872)
			(layers "*.Cu" "*.Mask")
			(remove_unused_layers no)
			(net "GND")
			(clearance 0.0508)
			(thermal_gap 0.0508)
		)
		(pad "M4" thru_hole circle
			(at 5.999988 14.59992 180)
			(size 0.906272 0.906272)
			(drill 0.499872)
			(layers "*.Cu" "*.Mask")
			(remove_unused_layers no)
			(net "GND")
			(clearance 0.0508)
			(thermal_gap 0.0508)
		)
		(pad "M6" thru_hole circle
			(at 9.99998 14.59992 180)
			(size 0.906272 0.906272)
			(drill 0.499872)
			(layers "*.Cu" "*.Mask")
			(remove_unused_layers no)
			(net "GND")
			(clearance 0.0508)
			(thermal_gap 0.0508)
		)
		(pad "M8" thru_hole circle
			(at 13.999972 14.59992 180)
			(size 0.906272 0.906272)
			(drill 0.499872)
			(layers "*.Cu" "*.Mask")
			(remove_unused_layers no)
			(net "GND")
			(clearance 0.0508)
			(thermal_gap 0.0508)
		)
		(pad "N1" thru_hole circle
			(at 0 15.599918 180)
			(size 0.906272 0.906272)
			(drill 0.499872)
			(layers "*.Cu" "*.Mask")
			(remove_unused_layers no)
			(net "GND")
			(clearance 0.0508)
			(thermal_gap 0.0508)
		)
		(pad "N2" thru_hole circle
			(at 1.999996 15.80007 180)
			(size 0.766318 0.766318)
			(drill 0.359918)
			(layers "*.Cu" "*.Mask")
			(remove_unused_layers no)
			(net "NC_J108_N2")
			(clearance 0.0508)
			(thermal_gap 0.0508)
		)
		(pad "N3" thru_hole circle
			(at 3.999992 15.599918 180)
			(size 0.906272 0.906272)
			(drill 0.499872)
			(layers "*.Cu" "*.Mask")
			(remove_unused_layers no)
			(net "GND")
			(clearance 0.0508)
			(thermal_gap 0.0508)
		)
		(pad "N4" thru_hole circle
			(at 5.999988 15.80007 180)
			(size 0.766318 0.766318)
			(drill 0.359918)
			(layers "*.Cu" "*.Mask")
			(remove_unused_layers no)
			(net "NC_J108_N4")
			(clearance 0.0508)
			(thermal_gap 0.0508)
		)
		(pad "N5" thru_hole circle
			(at 7.999984 15.599918 180)
			(size 0.906272 0.906272)
			(drill 0.499872)
			(layers "*.Cu" "*.Mask")
			(remove_unused_layers no)
			(net "GND")
			(clearance 0.0508)
			(thermal_gap 0.0508)
		)
		(pad "N6" thru_hole circle
			(at 9.99998 15.80007 180)
			(size 0.766318 0.766318)
			(drill 0.359918)
			(layers "*.Cu" "*.Mask")
			(remove_unused_layers no)
			(net "NC_J108_N6")
			(clearance 0.0508)
			(thermal_gap 0.0508)
		)
		(pad "N7" thru_hole circle
			(at 11.999976 15.599918 180)
			(size 0.906272 0.906272)
			(drill 0.499872)
			(layers "*.Cu" "*.Mask")
			(remove_unused_layers no)
			(net "GND")
			(clearance 0.0508)
			(thermal_gap 0.0508)
		)
		(pad "N8" thru_hole circle
			(at 13.999972 15.80007 180)
			(size 0.766318 0.766318)
			(drill 0.359918)
			(layers "*.Cu" "*.Mask")
			(remove_unused_layers no)
			(net "PRSNT_CABLE_GPU_A3_N")
			(clearance 0.0508)
			(thermal_gap 0.0508)
		)
	)
)
